(kicad_pcb
	(version 20260206)
	(generator "pcbnew")
	(generator_version "10.0")
	(general
		(thickness 1.6)
		(legacy_teardrops no)
	)
	(paper "A4")
	(title_block
		(title "baseboard — 13948-1b.1110WZS1818.brd")
		(comment 1 "Honey Badger (Wiwynn) / footprints 1159-1165 of 2523")
	)
	(layers
		(0 "F.Cu" signal "TOP")
		(4 "In1.Cu" signal "L2GND")
		(6 "In2.Cu" signal "L3")
		(8 "In3.Cu" signal "L4VCC")
		(10 "In4.Cu" signal "L5VCC")
		(12 "In5.Cu" signal "L6")
		(14 "In6.Cu" signal "L7GND")
		(2 "B.Cu" signal "BOTTOM")
		(9 "F.Adhes" user "F.Adhesive")
		(11 "B.Adhes" user "B.Adhesive")
		(13 "F.Paste" user "Package Geometry/Pastemask Top")
		(15 "B.Paste" user "Package Geometry/Pastemask Bottom")
		(5 "F.SilkS" user "Ref Des/Silkscreen Top")
		(7 "B.SilkS" user "Ref Des/Silkscreen Bottom")
		(1 "F.Mask" user "Board Geometry/Soldermask Top")
		(3 "B.Mask" user "Board Geometry/Soldermask Bottom")
		(17 "Dwgs.User" user "User.Drawings")
		(19 "Cmts.User" user "User.Comments")
		(21 "Eco1.User" user "User.Eco1")
		(23 "Eco2.User" user "User.Eco2")
		(25 "Edge.Cuts" user "Board Geometry/Outline")
		(27 "Margin" user)
		(31 "F.CrtYd" user "Package Geometry/Place Bound Top")
		(29 "B.CrtYd" user "Package Geometry/Place Bound Bottom")
		(35 "F.Fab" user "Ref Des/Assembly Top")
		(33 "B.Fab" user "Ref Des/Assembly Bottom")
	)
	(footprint ""
		(layer "F.Cu")
		(at 188.149992 -38.227 180)
		(property "Reference" "R379"
			(at 0 0 180)
			(layer "F.SilkS")
			(hide yes)
			(effects
				(font
					(size 1.27 1.27)
				)
			)
		)
		(property "Value" "33R2J-2-GP"
			(at 0.064008 -3.993896 180)
			(unlocked yes)
			(layer "F.Fab")
			(hide yes)
			(effects
				(font
					(size 1.016 1.016)
					(thickness 0.1524)
				)
			)
		)
		(property "Device Type" "R402H16"
			(at 0.064008 -5.517896 180)
			(unlocked yes)
			(layer "F.Fab")
			(hide yes)
			(effects
				(font
					(size 1.016 1.016)
					(thickness 0.1524)
				)
			)
		)
		(duplicate_pad_numbers_are_jumpers no)
		(fp_line
			(start 0.508 -0.9398)
			(end -0.508 -0.9398)
			(stroke
				(width 0.1524)
				(type default)
			)
			(layer "F.SilkS")
		)
		(fp_line
			(start -0.508 -0.9398)
			(end -0.508 0.9398)
			(stroke
				(width 0.1524)
				(type default)
			)
			(layer "F.SilkS")
		)
		(fp_rect
			(start -0.508 0.9398)
			(end 0.508 -0.9398)
			(stroke
				(width 0)
				(type default)
			)
			(fill no)
			(layer "F.CrtYd")
		)
		(fp_rect
			(start -0.508 0.9398)
			(end 0.508 -0.9398)
			(stroke
				(width 0)
				(type default)
			)
			(fill no)
			(layer "F.Fab")
		)
		(pad "1" smd custom
			(at 0 -0.4445 180)
			(size 0.1397 0.1397)
			(layers "F.Cu" "F.Mask" "F.Paste")
			(net "RMII_BMC_CRS_DV_R")
			(options
				(clearance outline)
				(anchor circle)
			)
			(primitives
				(gr_poly
					(pts
						(arc
							(start -0.1778 -0.2794)
							(mid -0.249642 -0.249642)
							(end -0.2794 -0.1778)
						)
						(arc
							(start -0.2794 0.1778)
							(mid -0.249642 0.249642)
							(end -0.1778 0.2794)
						)
						(arc
							(start 0.1778 0.2794)
							(mid 0.249642 0.249642)
							(end 0.2794 0.1778)
						)
						(arc
							(start 0.2794 -0.1778)
							(mid 0.249642 -0.249642)
							(end 0.1778 -0.2794)
						)
					)
					(width 0)
					(fill yes)
				)
			)
		)
		(pad "2" smd custom
			(at 0 0.4445 180)
			(size 0.1397 0.1397)
			(layers "F.Cu" "F.Mask" "F.Paste")
			(net "RMII_BMC_CRS_DV")
			(options
				(clearance outline)
				(anchor circle)
			)
			(primitives
				(gr_poly
					(pts
						(arc
							(start -0.1778 -0.2794)
							(mid -0.249642 -0.249642)
							(end -0.2794 -0.1778)
						)
						(arc
							(start -0.2794 0.1778)
							(mid -0.249642 0.249642)
							(end -0.1778 0.2794)
						)
						(arc
							(start 0.1778 0.2794)
							(mid 0.249642 0.249642)
							(end 0.2794 0.1778)
						)
						(arc
							(start 0.2794 -0.1778)
							(mid 0.249642 -0.249642)
							(end 0.1778 -0.2794)
						)
					)
					(width 0)
					(fill yes)
				)
			)
		)
	)
	(footprint ""
		(layer "F.Cu")
		(at 25.858216 -237.29188 180)
		(property "Reference" "SC427"
			(at 0 0 180)
			(layer "F.SilkS")
			(hide yes)
			(effects
				(font
					(size 1.27 1.27)
				)
			)
		)
		(property "Value" "SCD1U16V2KX-3GP"
			(at 1.1811 -2.7051 180)
			(unlocked yes)
			(layer "F.Fab")
			(hide yes)
			(effects
				(font
					(size 1.016 1.016)
					(thickness 0.1524)
				)
			)
		)
		(property "Device Type" "C402H22"
			(at 1.1811 -4.2291 180)
			(unlocked yes)
			(layer "F.Fab")
			(hide yes)
			(effects
				(font
					(size 1.016 1.016)
					(thickness 0.1524)
				)
			)
		)
		(duplicate_pad_numbers_are_jumpers no)
		(fp_rect
			(start -0.4318 0.9525)
			(end 0.4318 -0.9525)
			(stroke
				(width 0)
				(type default)
			)
			(fill no)
			(layer "F.CrtYd")
		)
		(fp_rect
			(start -0.4318 0.9525)
			(end 0.4318 -0.9525)
			(stroke
				(width 0)
				(type default)
			)
			(fill no)
			(layer "F.Fab")
		)
		(pad "1" smd custom
			(at 0 -0.4445 180)
			(size 0.1524 0.1524)
			(layers "F.Cu" "F.Mask" "F.Paste")
			(net "P3V3_STBY")
			(options
				(clearance outline)
				(anchor circle)
			)
			(primitives
				(gr_poly
					(pts
						(arc
							(start 0.3048 -0.2032)
							(mid 0.275042 -0.275042)
							(end 0.2032 -0.3048)
						)
						(arc
							(start -0.2032 -0.3048)
							(mid -0.275042 -0.275042)
							(end -0.3048 -0.2032)
						)
						(arc
							(start -0.3048 0.2032)
							(mid -0.275042 0.275042)
							(end -0.2032 0.3048)
						)
						(arc
							(start 0.2032 0.3048)
							(mid 0.275042 0.275042)
							(end 0.3048 0.2032)
						)
					)
					(width 0)
					(fill yes)
				)
			)
		)
		(pad "2" smd custom
			(at 0 0.4445 180)
			(size 0.1524 0.1524)
			(layers "F.Cu" "F.Mask" "F.Paste")
			(net "GND")
			(options
				(clearance outline)
				(anchor circle)
			)
			(primitives
				(gr_poly
					(pts
						(arc
							(start 0.3048 -0.2032)
							(mid 0.275042 -0.275042)
							(end 0.2032 -0.3048)
						)
						(arc
							(start -0.2032 -0.3048)
							(mid -0.275042 -0.275042)
							(end -0.3048 -0.2032)
						)
						(arc
							(start -0.3048 0.2032)
							(mid -0.275042 0.275042)
							(end -0.2032 0.3048)
						)
						(arc
							(start 0.2032 0.3048)
							(mid 0.275042 0.275042)
							(end 0.3048 0.2032)
						)
					)
					(width 0)
					(fill yes)
				)
			)
		)
	)
	(footprint ""
		(layer "F.Cu")
		(at 53.848 -180.086 180)
		(property "Reference" "SR810"
			(at 0 0 180)
			(layer "F.SilkS")
			(hide yes)
			(effects
				(font
					(size 1.27 1.27)
				)
			)
		)
		(property "Value" "4K75R2F-1-GP"
			(at 0.064008 -3.993896 180)
			(unlocked yes)
			(layer "F.Fab")
			(hide yes)
			(effects
				(font
					(size 1.016 1.016)
					(thickness 0.1524)
				)
			)
		)
		(property "Device Type" "R402H16"
			(at 0.064008 -5.517896 180)
			(unlocked yes)
			(layer "F.Fab")
			(hide yes)
			(effects
				(font
					(size 1.016 1.016)
					(thickness 0.1524)
				)
			)
		)
		(duplicate_pad_numbers_are_jumpers no)
		(fp_line
			(start 0.508 -0.9398)
			(end -0.508 -0.9398)
			(stroke
				(width 0.1524)
				(type default)
			)
			(layer "F.SilkS")
		)
		(fp_line
			(start -0.508 -0.9398)
			(end -0.508 0.9398)
			(stroke
				(width 0.1524)
				(type default)
			)
			(layer "F.SilkS")
		)
		(fp_rect
			(start -0.508 0.9398)
			(end 0.508 -0.9398)
			(stroke
				(width 0)
				(type default)
			)
			(fill no)
			(layer "F.CrtYd")
		)
		(fp_rect
			(start -0.508 0.9398)
			(end 0.508 -0.9398)
			(stroke
				(width 0)
				(type default)
			)
			(fill no)
			(layer "F.Fab")
		)
		(pad "1" smd custom
			(at 0 -0.4445 180)
			(size 0.1397 0.1397)
			(layers "F.Cu" "F.Mask" "F.Paste")
			(net "P1V8_E")
			(options
				(clearance outline)
				(anchor circle)
			)
			(primitives
				(gr_poly
					(pts
						(arc
							(start -0.1778 -0.2794)
							(mid -0.249642 -0.249642)
							(end -0.2794 -0.1778)
						)
						(arc
							(start -0.2794 0.1778)
							(mid -0.249642 0.249642)
							(end -0.1778 0.2794)
						)
						(arc
							(start 0.1778 0.2794)
							(mid 0.249642 0.249642)
							(end 0.2794 0.1778)
						)
						(arc
							(start 0.2794 -0.1778)
							(mid 0.249642 -0.249642)
							(end 0.1778 -0.2794)
						)
					)
					(width 0)
					(fill yes)
				)
			)
		)
		(pad "2" smd custom
			(at 0 0.4445 180)
			(size 0.1397 0.1397)
			(layers "F.Cu" "F.Mask" "F.Paste")
			(net "ICE_TDI")
			(options
				(clearance outline)
				(anchor circle)
			)
			(primitives
				(gr_poly
					(pts
						(arc
							(start -0.1778 -0.2794)
							(mid -0.249642 -0.249642)
							(end -0.2794 -0.1778)
						)
						(arc
							(start -0.2794 0.1778)
							(mid -0.249642 0.249642)
							(end -0.1778 0.2794)
						)
						(arc
							(start 0.1778 0.2794)
							(mid 0.249642 0.249642)
							(end 0.2794 0.1778)
						)
						(arc
							(start 0.2794 -0.1778)
							(mid 0.249642 -0.249642)
							(end 0.1778 -0.2794)
						)
					)
					(width 0)
					(fill yes)
				)
			)
		)
	)
	(footprint ""
		(layer "F.Cu")
		(at 80.64627 -79.540608 90)
		(property "Reference" "SR837"
			(at 0 0 90)
			(layer "F.SilkS")
			(hide yes)
			(effects
				(font
					(size 1.27 1.27)
				)
			)
		)
		(property "Value" "10R2F-L-GP"
			(at 0.064008 -3.993896 90)
			(unlocked yes)
			(layer "F.Fab")
			(hide yes)
			(effects
				(font
					(size 1.016 1.016)
					(thickness 0.1524)
				)
			)
		)
		(property "Device Type" "R402H14"
			(at 0.064008 -5.517896 90)
			(unlocked yes)
			(layer "F.Fab")
			(hide yes)
			(effects
				(font
					(size 1.016 1.016)
					(thickness 0.1524)
				)
			)
		)
		(duplicate_pad_numbers_are_jumpers no)
		(fp_line
			(start 0.508 -0.9398)
			(end -0.508 -0.9398)
			(stroke
				(width 0.1524)
				(type default)
			)
			(layer "F.SilkS")
		)
		(fp_line
			(start -0.508 -0.9398)
			(end -0.508 0.9398)
			(stroke
				(width 0.1524)
				(type default)
			)
			(layer "F.SilkS")
		)
		(fp_rect
			(start -0.508 0.9398)
			(end 0.508 -0.9398)
			(stroke
				(width 0)
				(type default)
			)
			(fill no)
			(layer "F.CrtYd")
		)
		(fp_rect
			(start -0.508 0.9398)
			(end 0.508 -0.9398)
			(stroke
				(width 0)
				(type default)
			)
			(fill no)
			(layer "F.Fab")
		)
		(pad "1" smd custom
			(at 0 -0.4445 90)
			(size 0.1397 0.1397)
			(layers "F.Cu" "F.Mask" "F.Paste")
			(net "P0V9_E")
			(options
				(clearance outline)
				(anchor circle)
			)
			(primitives
				(gr_poly
					(pts
						(arc
							(start -0.1778 -0.2794)
							(mid -0.249642 -0.249642)
							(end -0.2794 -0.1778)
						)
						(arc
							(start -0.2794 0.1778)
							(mid -0.249642 0.249642)
							(end -0.1778 0.2794)
						)
						(arc
							(start 0.1778 0.2794)
							(mid 0.249642 0.249642)
							(end 0.2794 0.1778)
						)
						(arc
							(start 0.2794 -0.1778)
							(mid 0.249642 -0.249642)
							(end 0.1778 -0.2794)
						)
					)
					(width 0)
					(fill yes)
				)
			)
		)
		(pad "2" smd custom
			(at 0 0.4445 90)
			(size 0.1397 0.1397)
			(layers "F.Cu" "F.Mask" "F.Paste")
			(net "XTAL_VDDA09")
			(options
				(clearance outline)
				(anchor circle)
			)
			(primitives
				(gr_poly
					(pts
						(arc
							(start -0.1778 -0.2794)
							(mid -0.249642 -0.249642)
							(end -0.2794 -0.1778)
						)
						(arc
							(start -0.2794 0.1778)
							(mid -0.249642 0.249642)
							(end -0.1778 0.2794)
						)
						(arc
							(start 0.1778 0.2794)
							(mid 0.249642 0.249642)
							(end 0.2794 0.1778)
						)
						(arc
							(start 0.2794 -0.1778)
							(mid 0.249642 -0.249642)
							(end 0.1778 -0.2794)
						)
					)
					(width 0)
					(fill yes)
				)
			)
		)
	)
	(footprint ""
		(layer "F.Cu")
		(at 267.7668 -76.0984 90)
		(property "Reference" "C262"
			(at 0 0 90)
			(layer "F.SilkS")
			(hide yes)
			(effects
				(font
					(size 1.27 1.27)
				)
			)
		)
		(property "Value" "SCD1U25V2KX-2-GP"
			(at 1.1811 -2.7051 90)
			(unlocked yes)
			(layer "F.Fab")
			(hide yes)
			(effects
				(font
					(size 1.016 1.016)
					(thickness 0.1524)
				)
			)
		)
		(property "Device Type" "C402H22"
			(at 1.1811 -4.2291 90)
			(unlocked yes)
			(layer "F.Fab")
			(hide yes)
			(effects
				(font
					(size 1.016 1.016)
					(thickness 0.1524)
				)
			)
		)
		(duplicate_pad_numbers_are_jumpers no)
		(fp_rect
			(start -0.4318 0.9525)
			(end 0.4318 -0.9525)
			(stroke
				(width 0)
				(type default)
			)
			(fill no)
			(layer "F.CrtYd")
		)
		(fp_rect
			(start -0.4318 0.9525)
			(end 0.4318 -0.9525)
			(stroke
				(width 0)
				(type default)
			)
			(fill no)
			(layer "F.Fab")
		)
		(pad "1" smd custom
			(at 0 -0.4445 90)
			(size 0.1524 0.1524)
			(layers "F.Cu" "F.Mask" "F.Paste")
			(net "P12V_MSB")
			(options
				(clearance outline)
				(anchor circle)
			)
			(primitives
				(gr_poly
					(pts
						(arc
							(start 0.3048 -0.2032)
							(mid 0.275042 -0.275042)
							(end 0.2032 -0.3048)
						)
						(arc
							(start -0.2032 -0.3048)
							(mid -0.275042 -0.275042)
							(end -0.3048 -0.2032)
						)
						(arc
							(start -0.3048 0.2032)
							(mid -0.275042 0.275042)
							(end -0.2032 0.3048)
						)
						(arc
							(start 0.2032 0.3048)
							(mid 0.275042 0.275042)
							(end 0.3048 0.2032)
						)
					)
					(width 0)
					(fill yes)
				)
			)
		)
		(pad "2" smd custom
			(at 0 0.4445 90)
			(size 0.1524 0.1524)
			(layers "F.Cu" "F.Mask" "F.Paste")
			(net "GND")
			(options
				(clearance outline)
				(anchor circle)
			)
			(primitives
				(gr_poly
					(pts
						(arc
							(start 0.3048 -0.2032)
							(mid 0.275042 -0.275042)
							(end 0.2032 -0.3048)
						)
						(arc
							(start -0.2032 -0.3048)
							(mid -0.275042 -0.275042)
							(end -0.3048 -0.2032)
						)
						(arc
							(start -0.3048 0.2032)
							(mid -0.275042 0.275042)
							(end -0.2032 0.3048)
						)
						(arc
							(start 0.2032 0.3048)
							(mid 0.275042 0.275042)
							(end 0.3048 0.2032)
						)
					)
					(width 0)
					(fill yes)
				)
			)
		)
	)
	(footprint ""
		(layer "F.Cu")
		(at 171.131992 -14.351 -90)
		(property "Reference" "R415"
			(at 0 0 270)
			(layer "F.SilkS")
			(hide yes)
			(effects
				(font
					(size 1.27 1.27)
				)
			)
		)
		(property "Value" "150R3J-L-GP"
			(at -0.0254 -2.5146 270)
			(unlocked yes)
			(layer "F.Fab")
			(hide yes)
			(effects
				(font
					(size 1.016 1.016)
					(thickness 0.1524)
				)
			)
		)
		(property "Device Type" "R603H22"
			(at -0.0254 -4.0386 270)
			(unlocked yes)
			(layer "F.Fab")
			(hide yes)
			(effects
				(font
					(size 1.016 1.016)
					(thickness 0.1524)
				)
			)
		)
		(duplicate_pad_numbers_are_jumpers no)
		(fp_line
			(start -0.4826 0)
			(end -0.2032 0)
			(stroke
				(width 0.2032)
				(type default)
			)
			(layer "F.SilkS")
		)
		(fp_line
			(start 0.2032 0)
			(end 0.4826 0)
			(stroke
				(width 0.2032)
				(type default)
			)
			(layer "F.SilkS")
		)
		(fp_rect
			(start -0.5842 1.3335)
			(end 0.5842 -1.3335)
			(stroke
				(width 0)
				(type default)
			)
			(fill no)
			(layer "F.CrtYd")
		)
		(fp_rect
			(start -0.5842 1.3335)
			(end 0.5842 -1.3335)
			(stroke
				(width 0)
				(type default)
			)
			(fill no)
			(layer "F.Fab")
		)
		(pad "1" smd custom
			(at 0 -0.762 270)
			(size 0.2159 0.2159)
			(layers "F.Cu" "F.Mask" "F.Paste")
			(net "P3V3_STBY")
			(options
				(clearance outline)
				(anchor circle)
			)
			(primitives
				(gr_poly
					(pts
						(arc
							(start -0.3302 -0.4318)
							(mid -0.402042 -0.402042)
							(end -0.4318 -0.3302)
						)
						(arc
							(start -0.4318 0.3302)
							(mid -0.402042 0.402042)
							(end -0.3302 0.4318)
						)
						(arc
							(start 0.3302 0.4318)
							(mid 0.402042 0.402042)
							(end 0.4318 0.3302)
						)
						(arc
							(start 0.4318 -0.3302)
							(mid 0.402042 -0.402042)
							(end 0.3302 -0.4318)
						)
					)
					(width 0)
					(fill yes)
				)
			)
		)
		(pad "2" smd custom
			(at 0 0.762 270)
			(size 0.2159 0.2159)
			(layers "F.Cu" "F.Mask" "F.Paste")
			(net "LED_MDI0_LINK")
			(options
				(clearance outline)
				(anchor circle)
			)
			(primitives
				(gr_poly
					(pts
						(arc
							(start -0.3302 -0.4318)
							(mid -0.402042 -0.402042)
							(end -0.4318 -0.3302)
						)
						(arc
							(start -0.4318 0.3302)
							(mid -0.402042 0.402042)
							(end -0.3302 0.4318)
						)
						(arc
							(start 0.3302 0.4318)
							(mid 0.402042 0.402042)
							(end 0.4318 0.3302)
						)
						(arc
							(start 0.4318 -0.3302)
							(mid 0.402042 -0.402042)
							(end 0.3302 -0.4318)
						)
					)
					(width 0)
					(fill yes)
				)
			)
		)
	)
	(footprint ""
		(layer "F.Cu")
		(at 173.981872 -202.637136 90)
		(property "Reference" "R151"
			(at 0 0 90)
			(layer "F.SilkS")
			(hide yes)
			(effects
				(font
					(size 1.27 1.27)
				)
			)
		)
		(property "Value" "0R2J-2-GP"
			(at 0.064008 -3.993896 90)
			(unlocked yes)
			(layer "F.Fab")
			(hide yes)
			(effects
				(font
					(size 1.016 1.016)
					(thickness 0.1524)
				)
			)
		)
		(property "Device Type" "R402H16"
			(at 0.064008 -5.517896 90)
			(unlocked yes)
			(layer "F.Fab")
			(hide yes)
			(effects
				(font
					(size 1.016 1.016)
					(thickness 0.1524)
				)
			)
		)
		(duplicate_pad_numbers_are_jumpers no)
		(fp_line
			(start 0.508 -0.9398)
			(end -0.508 -0.9398)
			(stroke
				(width 0.1524)
				(type default)
			)
			(layer "F.SilkS")
		)
		(fp_line
			(start -0.508 -0.9398)
			(end -0.508 0.9398)
			(stroke
				(width 0.1524)
				(type default)
			)
			(layer "F.SilkS")
		)
		(fp_rect
			(start -0.508 0.9398)
			(end 0.508 -0.9398)
			(stroke
				(width 0)
				(type default)
			)
			(fill no)
			(layer "F.CrtYd")
		)
		(fp_rect
			(start -0.508 0.9398)
			(end 0.508 -0.9398)
			(stroke
				(width 0)
				(type default)
			)
			(fill no)
			(layer "F.Fab")
		)
		(pad "1" smd custom
			(at 0 -0.4445 90)
			(size 0.1397 0.1397)
			(layers "F.Cu" "F.Mask" "F.Paste")
			(net "SAS_I2C_B_BUF_SCL_R")
			(options
				(clearance outline)
				(anchor circle)
			)
			(primitives
				(gr_poly
					(pts
						(arc
							(start -0.1778 -0.2794)
							(mid -0.249642 -0.249642)
							(end -0.2794 -0.1778)
						)
						(arc
							(start -0.2794 0.1778)
							(mid -0.249642 0.249642)
							(end -0.1778 0.2794)
						)
						(arc
							(start 0.1778 0.2794)
							(mid 0.249642 0.249642)
							(end 0.2794 0.1778)
						)
						(arc
							(start 0.2794 -0.1778)
							(mid 0.249642 -0.249642)
							(end 0.1778 -0.2794)
						)
					)
					(width 0)
					(fill yes)
				)
			)
		)
		(pad "2" smd custom
			(at 0 0.4445 90)
			(size 0.1397 0.1397)
			(layers "F.Cu" "F.Mask" "F.Paste")
			(net "SAS_I2C_B_BUF_SCL")
			(options
				(clearance outline)
				(anchor circle)
			)
			(primitives
				(gr_poly
					(pts
						(arc
							(start -0.1778 -0.2794)
							(mid -0.249642 -0.249642)
							(end -0.2794 -0.1778)
						)
						(arc
							(start -0.2794 0.1778)
							(mid -0.249642 0.249642)
							(end -0.1778 0.2794)
						)
						(arc
							(start 0.1778 0.2794)
							(mid 0.249642 0.249642)
							(end 0.2794 0.1778)
						)
						(arc
							(start 0.2794 -0.1778)
							(mid 0.249642 -0.249642)
							(end 0.1778 -0.2794)
						)
					)
					(width 0)
					(fill yes)
				)
			)
		)
	)
)
